# S9S_MB_2U (Grand Teton) — schematic netlist excerpt (pin names and nets, part order shuffled) for the footprints in the layout excerpt that follows; sources: Cadence DE-HDL packaged netlist, KiCad conversion of 03242023_DA0F0TMBIJ0_F0T_Motherboard_J_brd_V01_OCP.brd

J7  SCONN288_ADR50017P130CC  SCONN288_ADR50017-P130CC IO  pkg DDR288S_1-1VXB  page 88
  VIN_BULK0  = P12V_S3_AUX_CPU0_NVDIMM
  RFU0  = TP_CHD_CPU0_DIMM1_FRU_0
  VIN_MGMT  = P3V3_AUX
  HSCL  = I3C_SPD_DDRABCD_CPU0_LVC1_SCL_6
  HSDA  = I3C_SPD_DDRABCD_CPU0_LVC1_SDA
  VSS0  = GND
  DQ0_A  = M_D_CPU0_SA_DQ<0>
  VSS1  = GND
  DQ1_A  = M_D_CPU0_SA_DQ<1>
  VSS2  = GND
  DQS0_A_T  = M_D_CPU0_SA_DQS_DP<0>
  DQS0_A_C  = M_D_CPU0_SA_DQS_DN<0>
  VSS3  = GND
  DQ4_A  = M_D_CPU0_SA_DQ<4>
  VSS4  = GND
  DQ5_A  = M_D_CPU0_SA_DQ<5>
  VSS5  = GND
  DQ8_A  = M_D_CPU0_SA_DQ<8>
  VSS6  = GND
  DQ9_A  = M_D_CPU0_SA_DQ<9>
  VSS7  = GND
  DQS1_A_T  = M_D_CPU0_SA_DQS_DP<1>
  DQS1_A_C  = M_D_CPU0_SA_DQS_DN<1>
  VSS8  = GND
  DQ12_A  = M_D_CPU0_SA_DQ<12>
  VSS9  = GND
  DQ13_A  = M_D_CPU0_SA_DQ<13>
  VSS10  = GND
  DQ16_A  = M_D_CPU0_SA_DQ<16>
  VSS11  = GND
  DQ17_A  = M_D_CPU0_SA_DQ<17>
  VSS12  = GND
  DQS2_A_T  = M_D_CPU0_SA_DQS_DP<2>
  DQS2_A_C  = M_D_CPU0_SA_DQS_DN<2>
  VSS13  = GND
  DQ20_A  = M_D_CPU0_SA_DQ<20>
  VSS14  = GND
  DQ21_A  = M_D_CPU0_SA_DQ<21>
  VSS15  = GND
  DQ24_A  = M_D_CPU0_SA_DQ<24>
  VSS16  = GND
  DQ25_A  = M_D_CPU0_SA_DQ<25>
  VSS17  = GND
  DQS3_A_T  = M_D_CPU0_SA_DQS_DP<3>
  DQS3_A_C  = M_D_CPU0_SA_DQS_DN<3>
  VSS18  = GND
  DQ28_A  = M_D_CPU0_SA_DQ<28>
  VSS19  = GND
  DQ29_A  = M_D_CPU0_SA_DQ<29>
  VSS20  = GND
  CB0_A  = M_D_CPU0_SA_CB<0>
  VSS21  = GND
  CB1_A  = M_D_CPU0_SA_CB<1>
  VSS22  = GND
  DQS4_A_T  = M_D_CPU0_SA_DQS_DP<4>
  DQS4_A_C  = M_D_CPU0_SA_DQS_DN<4>
  VSS23  = GND
  CB4_A  = M_D_CPU0_SA_CB<4>
  VSS24  = GND
  CB5_A  = M_D_CPU0_SA_CB<5>
  VSS25  = GND
  ALERT_N  = M_D_CPU0_ALERT_N
  VSS26  = GND
  CS0_A_N  = M_D_CPU0_SA_CS_N<0>
  VSS27  = GND
  CA0_A  = M_D_CPU0_SA_CA<0>
  VSS28  = GND
  CA2_A  = M_D_CPU0_SA_CA<2>
  VSS29  = GND
  CA4_A  = M_D_CPU0_SA_CA<4>
  VSS30  = GND
  CA6_A  = M_D_CPU0_SA_CA<6>
  VSS31  = GND
  PAR_A  = M_D_CPU0_SA_PAR
  VSS32  = GND
  CA0_B  = M_D_CPU0_SB_CA<0>
  VSS33  = GND
  CA2_B  = M_D_CPU0_SB_CA<2>
  VSS34  = GND
  CA4_B  = M_D_CPU0_SB_CA<4>
  VSS35  = GND
  CA6_B  = M_D_CPU0_SB_CA<6>
  VSS36  = GND
  CS0_B_N  = M_D_CPU0_SB_CS_N<0>
  VSS37  = GND
  \lbd||rsp_a_n\  = M_D_CPU0_SA_RSP<0>
  \lbs||rsp_b_n\  = M_D_CPU0_SB_RSP<0>
  VSS38  = GND
  CB4_B  = M_D_CPU0_SB_CB<4>
  VSS39  = GND
  CB5_B  = M_D_CPU0_SB_CB<5>
  VSS40  = GND
  \dqs9_b_t||tdqs9_b_t||dbi4_b_n\  = M_D_CPU0_SB_DQS_DP<9>
  \dqs9_b_c||tdqs9_b_c\  = M_D_CPU0_SB_DQS_DN<9>
  VSS41  = GND
  CB0_B  = M_D_CPU0_SB_CB<0>
  VSS42  = GND
  CB1_B  = M_D_CPU0_SB_CB<1>
  VSS43  = GND
  DQ0_B  = M_D_CPU0_SB_DQ<0>
  VSS44  = GND
  DQ1_B  = M_D_CPU0_SB_DQ<1>
  VSS45  = GND
  DQS0_B_T  = M_D_CPU0_SB_DQS_DP<0>
  DQS0_B_C  = M_D_CPU0_SB_DQS_DN<0>
  VSS46  = GND
  DQ4_B  = M_D_CPU0_SB_DQ<4>
  VSS47  = GND
  DQ5_B  = M_D_CPU0_SB_DQ<5>
  VSS48  = GND
  DQ8_B  = M_D_CPU0_SB_DQ<8>
  VSS49  = GND
  DQ9_B  = M_D_CPU0_SB_DQ<9>
  VSS50  = GND
  DQS1_B_T  = M_D_CPU0_SB_DQS_DP<1>
  DQS1_B_C  = M_D_CPU0_SB_DQS_DN<1>
  VSS51  = GND
  DQ12_B  = M_D_CPU0_SB_DQ<12>
  VSS52  = GND
  DQ13_B  = M_D_CPU0_SB_DQ<13>
  VSS53  = GND
  DQ16_B  = M_D_CPU0_SB_DQ<16>
  VSS54  = GND
  DQ17_B  = M_D_CPU0_SB_DQ<17>
  VSS55  = GND
  DQS2_B_T  = M_D_CPU0_SB_DQS_DP<2>
  DQS2_B_C  = M_D_CPU0_SB_DQS_DN<2>
  VSS56  = GND
  DQ20_B  = M_D_CPU0_SB_DQ<20>
  VSS57  = GND
  DQ21_B  = M_D_CPU0_SB_DQ<21>
  VSS58  = GND
  DQ24_B  = M_D_CPU0_SB_DQ<24>
  VSS59  = GND
  DQ25_B  = M_D_CPU0_SB_DQ<25>
  VSS60  = GND
  DQS3_B_T  = M_D_CPU0_SB_DQS_DP<3>
  DQS3_B_C  = M_D_CPU0_SB_DQS_DN<3>
  VSS61  = GND
  DQ28_B  = M_D_CPU0_SB_DQ<28>
  VSS62  = GND
  DQ29_B  = M_D_CPU0_SB_DQ<29>
  VSS63  = GND
  RFU1  = TP_CHD_CPU0_DIMM1_FRU_1
  VIN_BULK1  = P12V_S3_AUX_CPU0_NVDIMM
  VIN_BULK2  = P12V_S3_AUX_CPU0_NVDIMM
  \pwr_good||fail_n\  = PWRGD_CHD_CPU0_DIMM1
  HSA  = PD_CHD_CPU0_DIMM1_SAA
  RFU2  = TP_CHD_CPU0_DIMM1_FRU_2
  RFU3  = TP_CHD_CPU0_DIMM1_FRU_3
  VSS64  = GND
  DQ2_A  = M_D_CPU0_SA_DQ<2>
  VSS65  = GND
  DQ3_A  = M_D_CPU0_SA_DQ<3>
  VSS66  = GND
  \dqs5_a_c||tdqs5_a_c||dqs5_a_t||tdqs5_a_t\  = M_D_CPU0_SA_DQS_DN<5>
  \dqs5_a_t||tdqs5_a_t\  = M_D_CPU0_SA_DQS_DP<5>
  VSS67  = GND
  DQ6_A  = M_D_CPU0_SA_DQ<6>
  VSS68  = GND
  DQ7_A  = M_D_CPU0_SA_DQ<7>
  VSS69  = GND
  DQ10_A  = M_D_CPU0_SA_DQ<10>
  VSS70  = GND
  DQ11_A  = M_D_CPU0_SA_DQ<11>
  VSS71  = GND
  \dqs6_a_c||tdqs6_a_c||dqs6_a_t||tdqs6_a_t\  = M_D_CPU0_SA_DQS_DN<6>
  \dqs6_a_t||tdqs6_a_t\  = M_D_CPU0_SA_DQS_DP<6>
  VSS72  = GND
  DQ14_A  = M_D_CPU0_SA_DQ<14>
  VSS73  = GND
  DQ15_A  = M_D_CPU0_SA_DQ<15>
  VSS74  = GND
  DQ18_A  = M_D_CPU0_SA_DQ<18>
  VSS75  = GND
  DQ19_A  = M_D_CPU0_SA_DQ<19>
  VSS76  = GND
  \dqs7_a_c||tdqs7_a_c\  = M_D_CPU0_SA_DQS_DN<7>
  \dqs7_a_t||tdqs7_a_t\  = M_D_CPU0_SA_DQS_DP<7>
  VSS77  = GND
  DQ22_A  = M_D_CPU0_SA_DQ<22>
  VSS78  = GND
  DQ23_A  = M_D_CPU0_SA_DQ<23>
  VSS79  = GND
  DQ26_A  = M_D_CPU0_SA_DQ<26>
  VSS80  = GND
  DQ27_A  = M_D_CPU0_SA_DQ<27>
  VSS81  = GND
  \dqs8_a_c||tdqs8_a_c\  = M_D_CPU0_SA_DQS_DN<8>
  \dqs8_a_t||tdqs8_a_t\  = M_D_CPU0_SA_DQS_DP<8>
  VSS82  = GND
  DQ30_A  = M_D_CPU0_SA_DQ<30>
  VSS83  = GND
  DQ31_A  = M_D_CPU0_SA_DQ<31>
  VSS84  = GND
  CB2_A  = M_D_CPU0_SA_CB<2>
  VSS85  = GND
  CB3_A  = M_D_CPU0_SA_CB<3>
  VSS86  = GND
  \dqs9_a_c||tdqs9_a_c\  = M_D_CPU0_SA_DQS_DN<9>
  \dqs9_a_t||tdqs9_a_t\  = M_D_CPU0_SA_DQS_DP<9>
  VSS87  = GND
  CB6_A  = M_D_CPU0_SA_CB<6>
  VSS88  = GND
  CB7_A  = M_D_CPU0_SA_CB<7>
  VSS89  = GND
  RESET_N  = RST_M_CD_CPU0_FPGA_N
  VSS90  = GND
  CS1_A_N  = M_D_CPU0_SA_CS_N<1>
  VSS91  = GND
  CA1_A  = M_D_CPU0_SA_CA<1>
  VSS92  = GND
  CA3_A  = M_D_CPU0_SA_CA<3>
  VSS93  = GND
  CA5_A  = M_D_CPU0_SA_CA<5>
  VSS94  = GND
  CK_T  = M_D_CPU0_CLK_DP<0>
  CK_C  = M_D_CPU0_CLK_DN<0>
  VSS95  = GND
  RFU4  = TP_CHD_CPU0_DIMM1_FRU_4
  CA1_B  = M_D_CPU0_SB_CA<1>
  VSS96  = GND
  CA3_B  = M_D_CPU0_SB_CA<3>
  VSS97  = GND
  CA5_B  = M_D_CPU0_SB_CA<5>
  VSS98  = GND
  PAR_B  = M_D_CPU0_SB_PAR
  VSS99  = GND
  CS1_B_N  = M_D_CPU0_SB_CS_N<1>
  VSS100  = GND
  RFU5  = TP_CHD_CPU0_DIMM1_FRU_5
  RFU6  = TP_CHD_CPU0_DIMM1_FRU_6
  VSS101  = GND
  CB6_B  = M_D_CPU0_SB_CB<6>
  VSS102  = GND
  CB7_B  = M_D_CPU0_SB_CB<7>
  VSS103  = GND
  DQS4_B_C  = M_D_CPU0_SB_DQS_DN<4>
  DQS4_B_T  = M_D_CPU0_SB_DQS_DP<4>
  VSS104  = GND
  CB2_B  = M_D_CPU0_SB_CB<2>
  VSS105  = GND
  CB3_B  = M_D_CPU0_SB_CB<3>
  VSS106  = GND
  DQ2_B  = M_D_CPU0_SB_DQ<2>
  VSS107  = GND
  DQ3_B  = M_D_CPU0_SB_DQ<3>
  VSS108  = GND
  \dqs5_b_c||tdqs5_b_c\  = M_D_CPU0_SB_DQS_DN<5>
  \dqs5_b_t||tdqs5_b_t\  = M_D_CPU0_SB_DQS_DP<5>
  VSS109  = GND
  DQ6_B  = M_D_CPU0_SB_DQ<6>
  VSS110  = GND
  DQ7_B  = M_D_CPU0_SB_DQ<7>
  VSS111  = GND
  DQ10_B  = M_D_CPU0_SB_DQ<10>
  VSS112  = GND
  DQ11_B  = M_D_CPU0_SB_DQ<11>
  VSS113  = GND
  \dqs6_b_c||tdqs6_b_c\  = M_D_CPU0_SB_DQS_DN<6>
  \dqs6_b_t||tdqs6_b_t\  = M_D_CPU0_SB_DQS_DP<6>
  VSS114  = GND
  DQ14_B  = M_D_CPU0_SB_DQ<14>
  VSS115  = GND
  DQ15_B  = M_D_CPU0_SB_DQ<15>
  VSS116  = GND
  DQ18_B  = M_D_CPU0_SB_DQ<18>
  VSS117  = GND
  DQ19_B  = M_D_CPU0_SB_DQ<19>
  VSS118  = GND
  \dqs7_b_c||tdqs7_b_c\  = M_D_CPU0_SB_DQS_DN<7>
  \dqs7_b_t||tdqs7_b_t\  = M_D_CPU0_SB_DQS_DP<7>
  VSS119  = GND
  DQ22_B  = M_D_CPU0_SB_DQ<22>
  VSS120  = GND
  DQ23_B  = M_D_CPU0_SB_DQ<23>
  VSS121  = GND
  DQ26_B  = M_D_CPU0_SB_DQ<26>
  VSS122  = GND
  DQ27_B  = M_D_CPU0_SB_DQ<27>
  VSS123  = GND
  \dqs8_b_c||tdqs8_b_c\  = M_D_CPU0_SB_DQS_DN<8>
  \dqs8_b_t||tdqs8_b_t\  = M_D_CPU0_SB_DQS_DP<8>
  VSS124  = GND
  DQ30_B  = M_D_CPU0_SB_DQ<30>
  VSS125  = GND
  DQ31_B  = M_D_CPU0_SB_DQ<31>
  VSS126  = GND
  G1  = GND
  G2  = GND
  G3  = GND

(kicad_pcb
	(version 20260206)
	(generator "pcbnew")
	(generator_version "10.0")
	(general
		(thickness 1.6)
		(legacy_teardrops no)
	)
	(paper "A4")
	(title_block
		(title "03242023_DA0F0TMBIJ0_F0T_Motherboard_J_brd_V01_OCP.brd")
		(comment 1 "Grand Teton / footprint 37 of 6105 (J7), pads 229-274 of 291")
	)
	(layers
		(0 "F.Cu" signal "TOP")
		(4 "In1.Cu" signal "GND")
		(6 "In2.Cu" signal "IN1")
		(8 "In3.Cu" signal "GND1")
		(10 "In4.Cu" signal "IN2")
		(12 "In5.Cu" signal "GND2")
		(14 "In6.Cu" signal "IN3")
		(16 "In7.Cu" signal "GND3")
		(18 "In8.Cu" signal "VCC")
		(20 "In9.Cu" signal "VCC1")
		(22 "In10.Cu" signal "GND4")
		(24 "In11.Cu" signal "IN4")
		(26 "In12.Cu" signal "GND5")
		(28 "In13.Cu" signal "IN5")
		(30 "In14.Cu" signal "GND6")
		(32 "In15.Cu" signal "IN6")
		(34 "In16.Cu" signal "GND7")
		(2 "B.Cu" signal "BOTTOM")
		(9 "F.Adhes" user "F.Adhesive")
		(11 "B.Adhes" user "B.Adhesive")
		(13 "F.Paste" user "Package Geometry/Pastemask Top")
		(15 "B.Paste" user "Package Geometry/Pastemask Bottom")
		(5 "F.SilkS" user "Ref Des/Silkscreen Top")
		(7 "B.SilkS" user "Ref Des/Silkscreen Bottom")
		(1 "F.Mask" user "Board Geometry/Soldermask Top")
		(3 "B.Mask" user "Board Geometry/Soldermask Bottom")
		(17 "Dwgs.User" user "User.Drawings")
		(19 "Cmts.User" user "User.Comments")
		(21 "Eco1.User" user "User.Eco1")
		(23 "Eco2.User" user "User.Eco2")
		(25 "Edge.Cuts" user "Board Geometry/Outline")
		(27 "Margin" user)
		(31 "F.CrtYd" user "Package Geometry/Place Bound Top")
		(29 "B.CrtYd" user "Package Geometry/Place Bound Bottom")
		(35 "F.Fab" user "Ref Des/Assembly Top")
		(33 "B.Fab" user "Ref Des/Assembly Bottom")
	)
	(footprint ""
		(layer "F.Cu")
		(at 258.130548 -258.091686)
		(property "Reference" "J7"
			(at -3.683 -81.702148 0)
			(unlocked yes)
			(layer "F.SilkS")
			(effects
				(font
					(size 0.7874 0.5842)
					(thickness 0.1524)
				)
				(justify left)
			)
		)
		(property "Value" ""
			(at 0 0 0)
			(layer "F.Fab")
			(effects
				(font
					(size 1.27 1.27)
				)
			)
		)
		(duplicate_pad_numbers_are_jumpers no)
		(pad "229" smd rect
			(at 2.050034 13.17498 270)
			(size 0.519938 1.4986)
			(layers "F.Cu" "F.Mask" "F.Paste")
			(net "M_D_CPU0_SB_CS_N<1>")
		)
		(pad "230" smd rect
			(at 2.050034 14.025118 270)
			(size 0.519938 1.4986)
			(layers "F.Cu" "F.Mask" "F.Paste")
			(net "GND")
		)
		(pad "231" smd rect
			(at 2.050034 14.875002 270)
			(size 0.519938 1.4986)
			(layers "F.Cu" "F.Mask" "F.Paste")
			(net "TP_CHD_CPU0_DIMM1_FRU_5")
		)
		(pad "232" smd rect
			(at 2.050034 15.724886 270)
			(size 0.519938 1.4986)
			(layers "F.Cu" "F.Mask" "F.Paste")
			(net "TP_CHD_CPU0_DIMM1_FRU_6")
		)
		(pad "233" smd rect
			(at 2.050034 16.575024 270)
			(size 0.519938 1.4986)
			(layers "F.Cu" "F.Mask" "F.Paste")
			(net "GND")
		)
		(pad "234" smd rect
			(at 2.050034 17.424908 270)
			(size 0.519938 1.4986)
			(layers "F.Cu" "F.Mask" "F.Paste")
			(net "M_D_CPU0_SB_CB<6>")
		)
		(pad "235" smd rect
			(at 2.050034 18.275046 270)
			(size 0.519938 1.4986)
			(layers "F.Cu" "F.Mask" "F.Paste")
			(net "GND")
		)
		(pad "236" smd rect
			(at 2.050034 19.12493 270)
			(size 0.519938 1.4986)
			(layers "F.Cu" "F.Mask" "F.Paste")
			(net "M_D_CPU0_SB_CB<7>")
		)
		(pad "237" smd rect
			(at 2.050034 19.975068 270)
			(size 0.519938 1.4986)
			(layers "F.Cu" "F.Mask" "F.Paste")
			(net "GND")
		)
		(pad "238" smd rect
			(at 2.050034 20.824952 270)
			(size 0.519938 1.4986)
			(layers "F.Cu" "F.Mask" "F.Paste")
			(net "M_D_CPU0_SB_DQS_DN<4>")
		)
		(pad "239" smd rect
			(at 2.050034 21.67509 270)
			(size 0.519938 1.4986)
			(layers "F.Cu" "F.Mask" "F.Paste")
			(net "M_D_CPU0_SB_DQS_DP<4>")
		)
		(pad "240" smd rect
			(at 2.050034 22.524974 270)
			(size 0.519938 1.4986)
			(layers "F.Cu" "F.Mask" "F.Paste")
			(net "GND")
		)
		(pad "241" smd rect
			(at 2.050034 23.375112 270)
			(size 0.519938 1.4986)
			(layers "F.Cu" "F.Mask" "F.Paste")
			(net "M_D_CPU0_SB_CB<2>")
		)
		(pad "242" smd rect
			(at 2.050034 24.224996 270)
			(size 0.519938 1.4986)
			(layers "F.Cu" "F.Mask" "F.Paste")
			(net "GND")
		)
		(pad "243" smd rect
			(at 2.050034 25.07488 270)
			(size 0.519938 1.4986)
			(layers "F.Cu" "F.Mask" "F.Paste")
			(net "M_D_CPU0_SB_CB<3>")
		)
		(pad "244" smd rect
			(at 2.050034 25.925018 270)
			(size 0.519938 1.4986)
			(layers "F.Cu" "F.Mask" "F.Paste")
			(net "GND")
		)
		(pad "245" smd rect
			(at 2.050034 26.774902 270)
			(size 0.519938 1.4986)
			(layers "F.Cu" "F.Mask" "F.Paste")
			(net "M_D_CPU0_SB_DQ<2>")
		)
		(pad "246" smd rect
			(at 2.050034 27.62504 270)
			(size 0.519938 1.4986)
			(layers "F.Cu" "F.Mask" "F.Paste")
			(net "GND")
		)
		(pad "247" smd rect
			(at 2.050034 28.474924 270)
			(size 0.519938 1.4986)
			(layers "F.Cu" "F.Mask" "F.Paste")
			(net "M_D_CPU0_SB_DQ<3>")
		)
		(pad "248" smd rect
			(at 2.050034 29.325062 270)
			(size 0.519938 1.4986)
			(layers "F.Cu" "F.Mask" "F.Paste")
			(net "GND")
		)
		(pad "249" smd rect
			(at 2.050034 30.174946 270)
			(size 0.519938 1.4986)
			(layers "F.Cu" "F.Mask" "F.Paste")
			(net "M_D_CPU0_SB_DQS_DN<5>")
		)
		(pad "250" smd rect
			(at 2.050034 31.025084 270)
			(size 0.519938 1.4986)
			(layers "F.Cu" "F.Mask" "F.Paste")
			(net "M_D_CPU0_SB_DQS_DP<5>")
		)
		(pad "251" smd rect
			(at 2.050034 31.874968 270)
			(size 0.519938 1.4986)
			(layers "F.Cu" "F.Mask" "F.Paste")
			(net "GND")
		)
		(pad "252" smd rect
			(at 2.050034 32.725106 270)
			(size 0.519938 1.4986)
			(layers "F.Cu" "F.Mask" "F.Paste")
			(net "M_D_CPU0_SB_DQ<6>")
		)
		(pad "253" smd rect
			(at 2.050034 33.57499 270)
			(size 0.519938 1.4986)
			(layers "F.Cu" "F.Mask" "F.Paste")
			(net "GND")
		)
		(pad "254" smd rect
			(at 2.050034 34.425128 270)
			(size 0.519938 1.4986)
			(layers "F.Cu" "F.Mask" "F.Paste")
			(net "M_D_CPU0_SB_DQ<7>")
		)
		(pad "255" smd rect
			(at 2.050034 35.275012 270)
			(size 0.519938 1.4986)
			(layers "F.Cu" "F.Mask" "F.Paste")
			(net "GND")
		)
		(pad "256" smd rect
			(at 2.050034 36.124896 270)
			(size 0.519938 1.4986)
			(layers "F.Cu" "F.Mask" "F.Paste")
			(net "M_D_CPU0_SB_DQ<10>")
		)
		(pad "257" smd rect
			(at 2.050034 36.975034 270)
			(size 0.519938 1.4986)
			(layers "F.Cu" "F.Mask" "F.Paste")
			(net "GND")
		)
		(pad "258" smd rect
			(at 2.050034 37.824918 270)
			(size 0.519938 1.4986)
			(layers "F.Cu" "F.Mask" "F.Paste")
			(net "M_D_CPU0_SB_DQ<11>")
		)
		(pad "259" smd rect
			(at 2.050034 38.675056 270)
			(size 0.519938 1.4986)
			(layers "F.Cu" "F.Mask" "F.Paste")
			(net "GND")
		)
		(pad "260" smd rect
			(at 2.050034 39.52494 270)
			(size 0.519938 1.4986)
			(layers "F.Cu" "F.Mask" "F.Paste")
			(net "M_D_CPU0_SB_DQS_DN<6>")
		)
		(pad "261" smd rect
			(at 2.050034 40.375078 270)
			(size 0.519938 1.4986)
			(layers "F.Cu" "F.Mask" "F.Paste")
			(net "M_D_CPU0_SB_DQS_DP<6>")
		)
		(pad "262" smd rect
			(at 2.050034 41.224962 270)
			(size 0.519938 1.4986)
			(layers "F.Cu" "F.Mask" "F.Paste")
			(net "GND")
		)
		(pad "263" smd rect
			(at 2.050034 42.0751 270)
			(size 0.519938 1.4986)
			(layers "F.Cu" "F.Mask" "F.Paste")
			(net "M_D_CPU0_SB_DQ<14>")
		)
		(pad "264" smd rect
			(at 2.050034 42.924984 270)
			(size 0.519938 1.4986)
			(layers "F.Cu" "F.Mask" "F.Paste")
			(net "GND")
		)
		(pad "265" smd rect
			(at 2.050034 43.775122 270)
			(size 0.519938 1.4986)
			(layers "F.Cu" "F.Mask" "F.Paste")
			(net "M_D_CPU0_SB_DQ<15>")
		)
		(pad "266" smd rect
			(at 2.050034 44.625006 270)
			(size 0.519938 1.4986)
			(layers "F.Cu" "F.Mask" "F.Paste")
			(net "GND")
		)
		(pad "267" smd rect
			(at 2.050034 45.47489 270)
			(size 0.519938 1.4986)
			(layers "F.Cu" "F.Mask" "F.Paste")
			(net "M_D_CPU0_SB_DQ<18>")
		)
		(pad "268" smd rect
			(at 2.050034 46.325028 270)
			(size 0.519938 1.4986)
			(layers "F.Cu" "F.Mask" "F.Paste")
			(net "GND")
		)
		(pad "269" smd rect
			(at 2.050034 47.174912 270)
			(size 0.519938 1.4986)
			(layers "F.Cu" "F.Mask" "F.Paste")
			(net "M_D_CPU0_SB_DQ<19>")
		)
		(pad "270" smd rect
			(at 2.050034 48.02505 270)
			(size 0.519938 1.4986)
			(layers "F.Cu" "F.Mask" "F.Paste")
			(net "GND")
		)
		(pad "271" smd rect
			(at 2.050034 48.874934 270)
			(size 0.519938 1.4986)
			(layers "F.Cu" "F.Mask" "F.Paste")
			(net "M_D_CPU0_SB_DQS_DN<7>")
		)
		(pad "272" smd rect
			(at 2.050034 49.725072 270)
			(size 0.519938 1.4986)
			(layers "F.Cu" "F.Mask" "F.Paste")
			(net "M_D_CPU0_SB_DQS_DP<7>")
		)
		(pad "273" smd rect
			(at 2.050034 50.574956 270)
			(size 0.519938 1.4986)
			(layers "F.Cu" "F.Mask" "F.Paste")
			(net "GND")
		)
		(pad "274" smd rect
			(at 2.050034 51.425094 270)
			(size 0.519938 1.4986)
			(layers "F.Cu" "F.Mask" "F.Paste")
			(net "M_D_CPU0_SB_DQ<22>")
		)
	)
)
